# S9S_MB_2U (Grand Teton) — schematic netlist excerpt (pin names and nets, part order shuffled) for the footprints in the layout excerpt that follows; sources: Cadence DE-HDL packaged netlist, KiCad conversion of 03242023_DA0F0TMBIJ0_F0T_Motherboard_J_brd_V01_OCP.brd

R1295  Q_RES  0 5% CHIP  pkg 0402LF  page 154 : A = NCSI_BMC_TXD0_R ; B = RMII_BMC_OCP_TXD_0
R4688  Q_RES  4.7K 1% EMPTY  pkg 0402LF  page 251 : A = GND ; B = HSC_TYPE_ADC_A0

(kicad_pcb
	(version 20260206)
	(generator "pcbnew")
	(generator_version "10.0")
	(general
		(thickness 1.6)
		(legacy_teardrops no)
	)
	(paper "A4")
	(title_block
		(title "03242023_DA0F0TMBIJ0_F0T_Motherboard_J_brd_V01_OCP.brd")
		(comment 1 "Grand Teton / footprints 108-109 of 6105")
	)
	(layers
		(0 "F.Cu" signal "TOP")
		(4 "In1.Cu" signal "GND")
		(6 "In2.Cu" signal "IN1")
		(8 "In3.Cu" signal "GND1")
		(10 "In4.Cu" signal "IN2")
		(12 "In5.Cu" signal "GND2")
		(14 "In6.Cu" signal "IN3")
		(16 "In7.Cu" signal "GND3")
		(18 "In8.Cu" signal "VCC")
		(20 "In9.Cu" signal "VCC1")
		(22 "In10.Cu" signal "GND4")
		(24 "In11.Cu" signal "IN4")
		(26 "In12.Cu" signal "GND5")
		(28 "In13.Cu" signal "IN5")
		(30 "In14.Cu" signal "GND6")
		(32 "In15.Cu" signal "IN6")
		(34 "In16.Cu" signal "GND7")
		(2 "B.Cu" signal "BOTTOM")
		(9 "F.Adhes" user "F.Adhesive")
		(11 "B.Adhes" user "B.Adhesive")
		(13 "F.Paste" user "Package Geometry/Pastemask Top")
		(15 "B.Paste" user "Package Geometry/Pastemask Bottom")
		(5 "F.SilkS" user "Ref Des/Silkscreen Top")
		(7 "B.SilkS" user "Ref Des/Silkscreen Bottom")
		(1 "F.Mask" user "Board Geometry/Soldermask Top")
		(3 "B.Mask" user "Board Geometry/Soldermask Bottom")
		(17 "Dwgs.User" user "User.Drawings")
		(19 "Cmts.User" user "User.Comments")
		(21 "Eco1.User" user "User.Eco1")
		(23 "Eco2.User" user "User.Eco2")
		(25 "Edge.Cuts" user "Board Geometry/Outline")
		(27 "Margin" user)
		(31 "F.CrtYd" user "Package Geometry/Place Bound Top")
		(29 "B.CrtYd" user "Package Geometry/Place Bound Bottom")
		(35 "F.Fab" user "Ref Des/Assembly Top")
		(33 "B.Fab" user "Ref Des/Assembly Bottom")
	)
	(footprint ""
		(layer "F.Cu")
		(at 209.069432 -71.09079)
		(property "Reference" "R1295"
			(at 0 0 0)
			(layer "F.SilkS")
			(hide yes)
			(effects
				(font
					(size 1.27 1.27)
				)
			)
		)
		(property "Value" ""
			(at 0 0 0)
			(layer "F.Fab")
			(effects
				(font
					(size 1.27 1.27)
				)
			)
		)
		(duplicate_pad_numbers_are_jumpers no)
		(fp_line
			(start -0.7874 -0.4064)
			(end 0.7874 -0.4064)
			(stroke
				(width 0.1524)
				(type default)
			)
			(layer "F.SilkS")
		)
		(fp_line
			(start -0.7874 0.4064)
			(end -0.7874 -0.4064)
			(stroke
				(width 0.1524)
				(type default)
			)
			(layer "F.SilkS")
		)
		(fp_line
			(start 0.7874 -0.4064)
			(end 0.7874 0.4064)
			(stroke
				(width 0.1524)
				(type default)
			)
			(layer "F.SilkS")
		)
		(fp_line
			(start 0.7874 0.4064)
			(end -0.7874 0.4064)
			(stroke
				(width 0.1524)
				(type default)
			)
			(layer "F.SilkS")
		)
		(fp_line
			(start -0.67945 -0.305054)
			(end -0.12065 -0.305054)
			(stroke
				(width 0.1)
				(type default)
			)
			(layer "F.Fab")
		)
		(fp_line
			(start -0.67945 0.3048)
			(end -0.67945 -0.305054)
			(stroke
				(width 0.1)
				(type default)
			)
			(layer "F.Fab")
		)
		(fp_line
			(start -0.12065 -0.305054)
			(end -0.12065 -0.2794)
			(stroke
				(width 0.1)
				(type default)
			)
			(layer "F.Fab")
		)
		(fp_line
			(start -0.12065 -0.2794)
			(end 0.12065 -0.2794)
			(stroke
				(width 0.1)
				(type default)
			)
			(layer "F.Fab")
		)
		(fp_line
			(start -0.12065 0.2794)
			(end -0.12065 0.3048)
			(stroke
				(width 0.1)
				(type default)
			)
			(layer "F.Fab")
		)
		(fp_line
			(start -0.12065 0.3048)
			(end -0.67945 0.3048)
			(stroke
				(width 0.1)
				(type default)
			)
			(layer "F.Fab")
		)
		(fp_line
			(start 0.120396 0.2794)
			(end -0.12065 0.2794)
			(stroke
				(width 0.1)
				(type default)
			)
			(layer "F.Fab")
		)
		(fp_line
			(start 0.120396 0.3048)
			(end 0.120396 0.2794)
			(stroke
				(width 0.1)
				(type default)
			)
			(layer "F.Fab")
		)
		(fp_line
			(start 0.12065 -0.3048)
			(end 0.67945 -0.3048)
			(stroke
				(width 0.1)
				(type default)
			)
			(layer "F.Fab")
		)
		(fp_line
			(start 0.12065 -0.2794)
			(end 0.12065 -0.3048)
			(stroke
				(width 0.1)
				(type default)
			)
			(layer "F.Fab")
		)
		(fp_line
			(start 0.67945 -0.3048)
			(end 0.67945 0.3048)
			(stroke
				(width 0.1)
				(type default)
			)
			(layer "F.Fab")
		)
		(fp_line
			(start 0.67945 0.3048)
			(end 0.120396 0.3048)
			(stroke
				(width 0.1)
				(type default)
			)
			(layer "F.Fab")
		)
		(pad "1" smd circle
			(at -0.40005 0)
			(size 0 0)
			(layers "F.Cu" "F.Mask" "F.Paste")
			(net "NCSI_BMC_TXD0_R")
		)
		(pad "2" smd circle
			(at 0.40005 0)
			(size 0 0)
			(layers "F.Cu" "F.Mask" "F.Paste")
			(net "RMII_BMC_OCP_TXD_0")
		)
	)
	(footprint ""
		(layer "F.Cu")
		(at 294.045894 -414.04286)
		(property "Reference" "R4688"
			(at 0 0 0)
			(layer "F.SilkS")
			(hide yes)
			(effects
				(font
					(size 1.27 1.27)
				)
			)
		)
		(property "Value" ""
			(at 0 0 0)
			(layer "F.Fab")
			(effects
				(font
					(size 1.27 1.27)
				)
			)
		)
		(duplicate_pad_numbers_are_jumpers no)
		(fp_line
			(start -0.7874 -0.4064)
			(end 0.7874 -0.4064)
			(stroke
				(width 0.1524)
				(type default)
			)
			(layer "F.SilkS")
		)
		(fp_line
			(start -0.7874 0.4064)
			(end -0.7874 -0.4064)
			(stroke
				(width 0.1524)
				(type default)
			)
			(layer "F.SilkS")
		)
		(fp_line
			(start 0.7874 -0.4064)
			(end 0.7874 0.4064)
			(stroke
				(width 0.1524)
				(type default)
			)
			(layer "F.SilkS")
		)
		(fp_line
			(start 0.7874 0.4064)
			(end -0.7874 0.4064)
			(stroke
				(width 0.1524)
				(type default)
			)
			(layer "F.SilkS")
		)
		(fp_line
			(start -0.67945 -0.305054)
			(end -0.12065 -0.305054)
			(stroke
				(width 0.1)
				(type default)
			)
			(layer "F.Fab")
		)
		(fp_line
			(start -0.67945 0.3048)
			(end -0.67945 -0.305054)
			(stroke
				(width 0.1)
				(type default)
			)
			(layer "F.Fab")
		)
		(fp_line
			(start -0.12065 -0.305054)
			(end -0.12065 -0.2794)
			(stroke
				(width 0.1)
				(type default)
			)
			(layer "F.Fab")
		)
		(fp_line
			(start -0.12065 -0.2794)
			(end 0.12065 -0.2794)
			(stroke
				(width 0.1)
				(type default)
			)
			(layer "F.Fab")
		)
		(fp_line
			(start -0.12065 0.2794)
			(end -0.12065 0.3048)
			(stroke
				(width 0.1)
				(type default)
			)
			(layer "F.Fab")
		)
		(fp_line
			(start -0.12065 0.3048)
			(end -0.67945 0.3048)
			(stroke
				(width 0.1)
				(type default)
			)
			(layer "F.Fab")
		)
		(fp_line
			(start 0.120396 0.2794)
			(end -0.12065 0.2794)
			(stroke
				(width 0.1)
				(type default)
			)
			(layer "F.Fab")
		)
		(fp_line
			(start 0.120396 0.3048)
			(end 0.120396 0.2794)
			(stroke
				(width 0.1)
				(type default)
			)
			(layer "F.Fab")
		)
		(fp_line
			(start 0.12065 -0.3048)
			(end 0.67945 -0.3048)
			(stroke
				(width 0.1)
				(type default)
			)
			(layer "F.Fab")
		)
		(fp_line
			(start 0.12065 -0.2794)
			(end 0.12065 -0.3048)
			(stroke
				(width 0.1)
				(type default)
			)
			(layer "F.Fab")
		)
		(fp_line
			(start 0.67945 -0.3048)
			(end 0.67945 0.3048)
			(stroke
				(width 0.1)
				(type default)
			)
			(layer "F.Fab")
		)
		(fp_line
			(start 0.67945 0.3048)
			(end 0.120396 0.3048)
			(stroke
				(width 0.1)
				(type default)
			)
			(layer "F.Fab")
		)
		(pad "1" smd circle
			(at -0.40005 0)
			(size 0 0)
			(layers "F.Cu" "F.Mask" "F.Paste")
			(net "GND")
		)
		(pad "2" smd circle
			(at 0.40005 0)
			(size 0 0)
			(layers "F.Cu" "F.Mask" "F.Paste")
			(net "HSC_TYPE_ADC_A0")
		)
	)
)
